(kicad_pcb
	(version 20260206)
	(generator "pcbnew")
	(generator_version "10.0")
	(general
		(thickness 1.6)
		(legacy_teardrops no)
	)
	(paper "A4")
	(title_block
		(title "12092022_DA0F0TFB6D0_F0T_FAN_BOARD_MP5048_D_brd_v02_OCP.brd")
		(comment 1 "Grand Teton / footprints 173-178 of 924")
	)
	(layers
		(0 "F.Cu" signal "TOP")
		(4 "In1.Cu" signal "GND")
		(6 "In2.Cu" signal "IN1")
		(8 "In3.Cu" signal "IN2")
		(10 "In4.Cu" signal "GND1")
		(2 "B.Cu" signal "BOTTOM")
		(9 "F.Adhes" user "F.Adhesive")
		(11 "B.Adhes" user "B.Adhesive")
		(13 "F.Paste" user "Package Geometry/Pastemask Top")
		(15 "B.Paste" user "Package Geometry/Pastemask Bottom")
		(5 "F.SilkS" user "Ref Des/Silkscreen Top")
		(7 "B.SilkS" user "Ref Des/Silkscreen Bottom")
		(1 "F.Mask" user "Board Geometry/Soldermask Top")
		(3 "B.Mask" user "Board Geometry/Soldermask Bottom")
		(17 "Dwgs.User" user "User.Drawings")
		(19 "Cmts.User" user "User.Comments")
		(21 "Eco1.User" user "User.Eco1")
		(23 "Eco2.User" user "User.Eco2")
		(25 "Edge.Cuts" user "Board Geometry/Outline")
		(27 "Margin" user)
		(31 "F.CrtYd" user "Package Geometry/Place Bound Top")
		(29 "B.CrtYd" user "Package Geometry/Place Bound Bottom")
		(35 "F.Fab" user "Ref Des/Assembly Top")
		(33 "B.Fab" user "Ref Des/Assembly Bottom")
	)
	(footprint ""
		(layer "F.Cu")
		(at 28.956 -172.593 180)
		(property "Reference" "R5108"
			(at 0 0 180)
			(layer "F.SilkS")
			(hide yes)
			(effects
				(font
					(size 1.27 1.27)
				)
			)
		)
		(property "Value" ""
			(at 0 0 180)
			(layer "F.Fab")
			(effects
				(font
					(size 1.27 1.27)
				)
			)
		)
		(duplicate_pad_numbers_are_jumpers no)
		(fp_line
			(start 0.7874 0.4064)
			(end -0.7874 0.4064)
			(stroke
				(width 0.1524)
				(type default)
			)
			(layer "F.SilkS")
		)
		(fp_line
			(start 0.7874 -0.4064)
			(end 0.7874 0.4064)
			(stroke
				(width 0.1524)
				(type default)
			)
			(layer "F.SilkS")
		)
		(fp_line
			(start -0.7874 0.4064)
			(end -0.7874 -0.4064)
			(stroke
				(width 0.1524)
				(type default)
			)
			(layer "F.SilkS")
		)
		(fp_line
			(start -0.7874 -0.4064)
			(end 0.7874 -0.4064)
			(stroke
				(width 0.1524)
				(type default)
			)
			(layer "F.SilkS")
		)
		(fp_line
			(start 0.67945 0.3048)
			(end 0.120396 0.3048)
			(stroke
				(width 0.1)
				(type default)
			)
			(layer "F.Fab")
		)
		(fp_line
			(start 0.67945 -0.3048)
			(end 0.67945 0.3048)
			(stroke
				(width 0.1)
				(type default)
			)
			(layer "F.Fab")
		)
		(fp_line
			(start 0.12065 -0.2794)
			(end 0.12065 -0.3048)
			(stroke
				(width 0.1)
				(type default)
			)
			(layer "F.Fab")
		)
		(fp_line
			(start 0.12065 -0.3048)
			(end 0.67945 -0.3048)
			(stroke
				(width 0.1)
				(type default)
			)
			(layer "F.Fab")
		)
		(fp_line
			(start 0.120396 0.3048)
			(end 0.120396 0.2794)
			(stroke
				(width 0.1)
				(type default)
			)
			(layer "F.Fab")
		)
		(fp_line
			(start 0.120396 0.2794)
			(end -0.12065 0.2794)
			(stroke
				(width 0.1)
				(type default)
			)
			(layer "F.Fab")
		)
		(fp_line
			(start -0.12065 0.3048)
			(end -0.67945 0.3048)
			(stroke
				(width 0.1)
				(type default)
			)
			(layer "F.Fab")
		)
		(fp_line
			(start -0.12065 0.2794)
			(end -0.12065 0.3048)
			(stroke
				(width 0.1)
				(type default)
			)
			(layer "F.Fab")
		)
		(fp_line
			(start -0.12065 -0.2794)
			(end 0.12065 -0.2794)
			(stroke
				(width 0.1)
				(type default)
			)
			(layer "F.Fab")
		)
		(fp_line
			(start -0.12065 -0.305054)
			(end -0.12065 -0.2794)
			(stroke
				(width 0.1)
				(type default)
			)
			(layer "F.Fab")
		)
		(fp_line
			(start -0.67945 0.3048)
			(end -0.67945 -0.305054)
			(stroke
				(width 0.1)
				(type default)
			)
			(layer "F.Fab")
		)
		(fp_line
			(start -0.67945 -0.305054)
			(end -0.12065 -0.305054)
			(stroke
				(width 0.1)
				(type default)
			)
			(layer "F.Fab")
		)
		(pad "1" smd circle
			(at -0.40005 0 180)
			(size 0 0)
			(layers "F.Cu" "F.Mask" "F.Paste")
			(net "FAN_6_FAIL_LED")
		)
		(pad "2" smd circle
			(at 0.40005 0 180)
			(size 0 0)
			(layers "F.Cu" "F.Mask" "F.Paste")
			(net "FAN_6_FAIL_R_LED")
		)
	)
	(footprint ""
		(layer "F.Cu")
		(at 16.764 -296.672 180)
		(property "Reference" "R5534"
			(at 0 0 180)
			(layer "F.SilkS")
			(hide yes)
			(effects
				(font
					(size 1.27 1.27)
				)
			)
		)
		(property "Value" ""
			(at 0 0 180)
			(layer "F.Fab")
			(effects
				(font
					(size 1.27 1.27)
				)
			)
		)
		(duplicate_pad_numbers_are_jumpers no)
		(fp_line
			(start 0.7874 0.4064)
			(end -0.7874 0.4064)
			(stroke
				(width 0.1524)
				(type default)
			)
			(layer "F.SilkS")
		)
		(fp_line
			(start 0.7874 -0.4064)
			(end 0.7874 0.4064)
			(stroke
				(width 0.1524)
				(type default)
			)
			(layer "F.SilkS")
		)
		(fp_line
			(start -0.7874 0.4064)
			(end -0.7874 -0.4064)
			(stroke
				(width 0.1524)
				(type default)
			)
			(layer "F.SilkS")
		)
		(fp_line
			(start -0.7874 -0.4064)
			(end 0.7874 -0.4064)
			(stroke
				(width 0.1524)
				(type default)
			)
			(layer "F.SilkS")
		)
		(fp_line
			(start 0.67945 0.3048)
			(end 0.120396 0.3048)
			(stroke
				(width 0.1)
				(type default)
			)
			(layer "F.Fab")
		)
		(fp_line
			(start 0.67945 -0.3048)
			(end 0.67945 0.3048)
			(stroke
				(width 0.1)
				(type default)
			)
			(layer "F.Fab")
		)
		(fp_line
			(start 0.12065 -0.2794)
			(end 0.12065 -0.3048)
			(stroke
				(width 0.1)
				(type default)
			)
			(layer "F.Fab")
		)
		(fp_line
			(start 0.12065 -0.3048)
			(end 0.67945 -0.3048)
			(stroke
				(width 0.1)
				(type default)
			)
			(layer "F.Fab")
		)
		(fp_line
			(start 0.120396 0.3048)
			(end 0.120396 0.2794)
			(stroke
				(width 0.1)
				(type default)
			)
			(layer "F.Fab")
		)
		(fp_line
			(start 0.120396 0.2794)
			(end -0.12065 0.2794)
			(stroke
				(width 0.1)
				(type default)
			)
			(layer "F.Fab")
		)
		(fp_line
			(start -0.12065 0.3048)
			(end -0.67945 0.3048)
			(stroke
				(width 0.1)
				(type default)
			)
			(layer "F.Fab")
		)
		(fp_line
			(start -0.12065 0.2794)
			(end -0.12065 0.3048)
			(stroke
				(width 0.1)
				(type default)
			)
			(layer "F.Fab")
		)
		(fp_line
			(start -0.12065 -0.2794)
			(end 0.12065 -0.2794)
			(stroke
				(width 0.1)
				(type default)
			)
			(layer "F.Fab")
		)
		(fp_line
			(start -0.12065 -0.305054)
			(end -0.12065 -0.2794)
			(stroke
				(width 0.1)
				(type default)
			)
			(layer "F.Fab")
		)
		(fp_line
			(start -0.67945 0.3048)
			(end -0.67945 -0.305054)
			(stroke
				(width 0.1)
				(type default)
			)
			(layer "F.Fab")
		)
		(fp_line
			(start -0.67945 -0.305054)
			(end -0.12065 -0.305054)
			(stroke
				(width 0.1)
				(type default)
			)
			(layer "F.Fab")
		)
		(pad "1" smd rect
			(at -0.40005 0)
			(size 0.4572 0.508)
			(layers "F.Cu" "F.Mask" "F.Paste")
			(net "P12V_LED_FAN7")
		)
		(pad "2" smd rect
			(at 0.40005 0)
			(size 0.4572 0.508)
			(layers "F.Cu" "F.Mask" "F.Paste")
			(net "FAN_7_FAIL_LED_R_N")
		)
	)
	(footprint ""
		(layer "F.Cu")
		(at 18.034 -303.911)
		(property "Reference" "R5323"
			(at 0 0 0)
			(layer "F.SilkS")
			(hide yes)
			(effects
				(font
					(size 1.27 1.27)
				)
			)
		)
		(property "Value" ""
			(at 0 0 0)
			(layer "F.Fab")
			(effects
				(font
					(size 1.27 1.27)
				)
			)
		)
		(duplicate_pad_numbers_are_jumpers no)
		(fp_line
			(start -0.7874 -0.4064)
			(end 0.7874 -0.4064)
			(stroke
				(width 0.1524)
				(type default)
			)
			(layer "F.SilkS")
		)
		(fp_line
			(start -0.7874 0.4064)
			(end -0.7874 -0.4064)
			(stroke
				(width 0.1524)
				(type default)
			)
			(layer "F.SilkS")
		)
		(fp_line
			(start 0.7874 -0.4064)
			(end 0.7874 0.4064)
			(stroke
				(width 0.1524)
				(type default)
			)
			(layer "F.SilkS")
		)
		(fp_line
			(start 0.7874 0.4064)
			(end -0.7874 0.4064)
			(stroke
				(width 0.1524)
				(type default)
			)
			(layer "F.SilkS")
		)
		(fp_line
			(start -0.67945 -0.305054)
			(end -0.12065 -0.305054)
			(stroke
				(width 0.1)
				(type default)
			)
			(layer "F.Fab")
		)
		(fp_line
			(start -0.67945 0.3048)
			(end -0.67945 -0.305054)
			(stroke
				(width 0.1)
				(type default)
			)
			(layer "F.Fab")
		)
		(fp_line
			(start -0.12065 -0.305054)
			(end -0.12065 -0.2794)
			(stroke
				(width 0.1)
				(type default)
			)
			(layer "F.Fab")
		)
		(fp_line
			(start -0.12065 -0.2794)
			(end 0.12065 -0.2794)
			(stroke
				(width 0.1)
				(type default)
			)
			(layer "F.Fab")
		)
		(fp_line
			(start -0.12065 0.2794)
			(end -0.12065 0.3048)
			(stroke
				(width 0.1)
				(type default)
			)
			(layer "F.Fab")
		)
		(fp_line
			(start -0.12065 0.3048)
			(end -0.67945 0.3048)
			(stroke
				(width 0.1)
				(type default)
			)
			(layer "F.Fab")
		)
		(fp_line
			(start 0.120396 0.2794)
			(end -0.12065 0.2794)
			(stroke
				(width 0.1)
				(type default)
			)
			(layer "F.Fab")
		)
		(fp_line
			(start 0.120396 0.3048)
			(end 0.120396 0.2794)
			(stroke
				(width 0.1)
				(type default)
			)
			(layer "F.Fab")
		)
		(fp_line
			(start 0.12065 -0.3048)
			(end 0.67945 -0.3048)
			(stroke
				(width 0.1)
				(type default)
			)
			(layer "F.Fab")
		)
		(fp_line
			(start 0.12065 -0.2794)
			(end 0.12065 -0.3048)
			(stroke
				(width 0.1)
				(type default)
			)
			(layer "F.Fab")
		)
		(fp_line
			(start 0.67945 -0.3048)
			(end 0.67945 0.3048)
			(stroke
				(width 0.1)
				(type default)
			)
			(layer "F.Fab")
		)
		(fp_line
			(start 0.67945 0.3048)
			(end 0.120396 0.3048)
			(stroke
				(width 0.1)
				(type default)
			)
			(layer "F.Fab")
		)
		(pad "1" smd rect
			(at -0.40005 0 180)
			(size 0.4572 0.508)
			(layers "F.Cu" "F.Mask" "F.Paste")
			(net "FAN_7_TACH_OL_R")
		)
		(pad "2" smd rect
			(at 0.40005 0 180)
			(size 0.4572 0.508)
			(layers "F.Cu" "F.Mask" "F.Paste")
			(net "FAN_7_TACH_OL")
		)
	)
	(footprint ""
		(layer "F.Cu")
		(at 19.558 -203.708 -90)
		(property "Reference" "R5370"
			(at 0 0 270)
			(layer "F.SilkS")
			(hide yes)
			(effects
				(font
					(size 1.27 1.27)
				)
			)
		)
		(property "Value" ""
			(at 0 0 270)
			(layer "F.Fab")
			(effects
				(font
					(size 1.27 1.27)
				)
			)
		)
		(duplicate_pad_numbers_are_jumpers no)
		(fp_line
			(start -0.7874 0.4064)
			(end -0.7874 -0.4064)
			(stroke
				(width 0.1524)
				(type default)
			)
			(layer "F.SilkS")
		)
		(fp_line
			(start 0.7874 0.4064)
			(end -0.7874 0.4064)
			(stroke
				(width 0.1524)
				(type default)
			)
			(layer "F.SilkS")
		)
		(fp_line
			(start -0.7874 -0.4064)
			(end 0.7874 -0.4064)
			(stroke
				(width 0.1524)
				(type default)
			)
			(layer "F.SilkS")
		)
		(fp_line
			(start 0.7874 -0.4064)
			(end 0.7874 0.4064)
			(stroke
				(width 0.1524)
				(type default)
			)
			(layer "F.SilkS")
		)
		(fp_line
			(start -0.67945 0.3048)
			(end -0.67945 -0.305054)
			(stroke
				(width 0.1)
				(type default)
			)
			(layer "F.Fab")
		)
		(fp_line
			(start -0.12065 0.3048)
			(end -0.67945 0.3048)
			(stroke
				(width 0.1)
				(type default)
			)
			(layer "F.Fab")
		)
		(fp_line
			(start 0.120396 0.3048)
			(end 0.120396 0.2794)
			(stroke
				(width 0.1)
				(type default)
			)
			(layer "F.Fab")
		)
		(fp_line
			(start 0.67945 0.3048)
			(end 0.120396 0.3048)
			(stroke
				(width 0.1)
				(type default)
			)
			(layer "F.Fab")
		)
		(fp_line
			(start -0.12065 0.2794)
			(end -0.12065 0.3048)
			(stroke
				(width 0.1)
				(type default)
			)
			(layer "F.Fab")
		)
		(fp_line
			(start 0.120396 0.2794)
			(end -0.12065 0.2794)
			(stroke
				(width 0.1)
				(type default)
			)
			(layer "F.Fab")
		)
		(fp_line
			(start -0.12065 -0.2794)
			(end 0.12065 -0.2794)
			(stroke
				(width 0.1)
				(type default)
			)
			(layer "F.Fab")
		)
		(fp_line
			(start 0.12065 -0.2794)
			(end 0.12065 -0.3048)
			(stroke
				(width 0.1)
				(type default)
			)
			(layer "F.Fab")
		)
		(fp_line
			(start 0.12065 -0.3048)
			(end 0.67945 -0.3048)
			(stroke
				(width 0.1)
				(type default)
			)
			(layer "F.Fab")
		)
		(fp_line
			(start 0.67945 -0.3048)
			(end 0.67945 0.3048)
			(stroke
				(width 0.1)
				(type default)
			)
			(layer "F.Fab")
		)
		(fp_line
			(start -0.67945 -0.305054)
			(end -0.12065 -0.305054)
			(stroke
				(width 0.1)
				(type default)
			)
			(layer "F.Fab")
		)
		(fp_line
			(start -0.12065 -0.305054)
			(end -0.12065 -0.2794)
			(stroke
				(width 0.1)
				(type default)
			)
			(layer "F.Fab")
		)
		(pad "1" smd circle
			(at -0.40005 0 270)
			(size 0 0)
			(layers "F.Cu" "F.Mask" "F.Paste")
			(net "P3V3_AUX")
		)
		(pad "2" smd circle
			(at 0.40005 0 270)
			(size 0 0)
			(layers "F.Cu" "F.Mask" "F.Paste")
			(net "FAN_6_FAIL_R_LED")
		)
	)
	(footprint ""
		(layer "F.Cu")
		(at 37.338 -108.712)
		(property "Reference" "D275"
			(at 0.127 1.29667 0)
			(unlocked yes)
			(layer "F.SilkS")
			(effects
				(font
					(size 0.7874 0.5842)
					(thickness 0.1524)
				)
				(justify left)
			)
		)
		(property "Value" ""
			(at 0 0 0)
			(layer "F.Fab")
			(effects
				(font
					(size 1.27 1.27)
				)
			)
		)
		(duplicate_pad_numbers_are_jumpers no)
		(fp_line
			(start -0.854964 -0.450088)
			(end -0.854964 0.450088)
			(stroke
				(width 0.1524)
				(type default)
			)
			(layer "F.SilkS")
		)
		(fp_line
			(start -0.854964 0.450088)
			(end 0.925068 0.450088)
			(stroke
				(width 0.1524)
				(type default)
			)
			(layer "F.SilkS")
		)
		(fp_line
			(start 0.845058 0.4064)
			(end 0.845058 -0.381)
			(stroke
				(width 0.1524)
				(type default)
			)
			(layer "F.SilkS")
		)
		(fp_line
			(start 0.870458 -0.2794)
			(end 0.845058 0.4064)
			(stroke
				(width 0.1524)
				(type default)
			)
			(layer "F.SilkS")
		)
		(fp_line
			(start 0.94488 -0.450088)
			(end -0.854964 -0.450088)
			(stroke
				(width 0.1524)
				(type default)
			)
			(layer "F.SilkS")
		)
		(fp_line
			(start 0.94488 0.450088)
			(end 0.94488 -0.450088)
			(stroke
				(width 0.1524)
				(type default)
			)
			(layer "F.SilkS")
		)
		(fp_line
			(start -0.54991 -0.350012)
			(end -0.54991 0.350012)
			(stroke
				(width 0.1)
				(type default)
			)
			(layer "F.Fab")
		)
		(fp_line
			(start -0.54991 0.350012)
			(end 0.54991 0.350012)
			(stroke
				(width 0.1)
				(type default)
			)
			(layer "F.Fab")
		)
		(fp_line
			(start 0.54991 -0.350012)
			(end -0.54991 -0.350012)
			(stroke
				(width 0.1)
				(type default)
			)
			(layer "F.Fab")
		)
		(fp_line
			(start 0.54991 0.350012)
			(end 0.54991 -0.350012)
			(stroke
				(width 0.1)
				(type default)
			)
			(layer "F.Fab")
		)
		(fp_text user "+"
			(at -0.56388 0.50927 180)
			(unlocked yes)
			(layer "F.SilkS")
			(effects
				(font
					(size 1.905 1.4224)
					(thickness 0.1524)
				)
				(justify left)
			)
		)
		(fp_text user "-"
			(at 2.26314 -0.40005 180)
			(unlocked yes)
			(layer "F.SilkS")
			(effects
				(font
					(size 1.905 1.4224)
					(thickness 0.1524)
				)
				(justify left)
			)
		)
		(fp_text user "+"
			(at -0.808228 0.239014 180)
			(unlocked yes)
			(layer "F.Fab")
			(effects
				(font
					(size 1.905 1.4224)
					(thickness 0.1524)
				)
				(justify left)
			)
		)
		(fp_text user "-"
			(at 2.48539 0.239014 180)
			(unlocked yes)
			(layer "F.Fab")
			(effects
				(font
					(size 1.905 1.4224)
					(thickness 0.1524)
				)
				(justify left)
			)
		)
		(pad "A" smd rect
			(at -0.424942 0)
			(size 0.5588 0.6096)
			(layers "F.Cu" "F.Mask" "F.Paste")
			(net "GND")
		)
		(pad "C" smd rect
			(at 0.424942 0 180)
			(size 0.5588 0.6096)
			(layers "F.Cu" "F.Mask" "F.Paste")
			(net "FAN_2_FAIL_R_LED_N")
		)
	)
	(footprint ""
		(layer "F.Cu")
		(at 48.26 -132.334 180)
		(property "Reference" "R5560"
			(at 0 0 180)
			(layer "F.SilkS")
			(hide yes)
			(effects
				(font
					(size 1.27 1.27)
				)
			)
		)
		(property "Value" ""
			(at 0 0 180)
			(layer "F.Fab")
			(effects
				(font
					(size 1.27 1.27)
				)
			)
		)
		(duplicate_pad_numbers_are_jumpers no)
		(fp_line
			(start 0.7874 0.4064)
			(end -0.7874 0.4064)
			(stroke
				(width 0.1524)
				(type default)
			)
			(layer "F.SilkS")
		)
		(fp_line
			(start 0.7874 -0.4064)
			(end 0.7874 0.4064)
			(stroke
				(width 0.1524)
				(type default)
			)
			(layer "F.SilkS")
		)
		(fp_line
			(start -0.7874 0.4064)
			(end -0.7874 -0.4064)
			(stroke
				(width 0.1524)
				(type default)
			)
			(layer "F.SilkS")
		)
		(fp_line
			(start -0.7874 -0.4064)
			(end 0.7874 -0.4064)
			(stroke
				(width 0.1524)
				(type default)
			)
			(layer "F.SilkS")
		)
		(fp_line
			(start 0.67945 0.3048)
			(end 0.120396 0.3048)
			(stroke
				(width 0.1)
				(type default)
			)
			(layer "F.Fab")
		)
		(fp_line
			(start 0.67945 -0.3048)
			(end 0.67945 0.3048)
			(stroke
				(width 0.1)
				(type default)
			)
			(layer "F.Fab")
		)
		(fp_line
			(start 0.12065 -0.2794)
			(end 0.12065 -0.3048)
			(stroke
				(width 0.1)
				(type default)
			)
			(layer "F.Fab")
		)
		(fp_line
			(start 0.12065 -0.3048)
			(end 0.67945 -0.3048)
			(stroke
				(width 0.1)
				(type default)
			)
			(layer "F.Fab")
		)
		(fp_line
			(start 0.120396 0.3048)
			(end 0.120396 0.2794)
			(stroke
				(width 0.1)
				(type default)
			)
			(layer "F.Fab")
		)
		(fp_line
			(start 0.120396 0.2794)
			(end -0.12065 0.2794)
			(stroke
				(width 0.1)
				(type default)
			)
			(layer "F.Fab")
		)
		(fp_line
			(start -0.12065 0.3048)
			(end -0.67945 0.3048)
			(stroke
				(width 0.1)
				(type default)
			)
			(layer "F.Fab")
		)
		(fp_line
			(start -0.12065 0.2794)
			(end -0.12065 0.3048)
			(stroke
				(width 0.1)
				(type default)
			)
			(layer "F.Fab")
		)
		(fp_line
			(start -0.12065 -0.2794)
			(end 0.12065 -0.2794)
			(stroke
				(width 0.1)
				(type default)
			)
			(layer "F.Fab")
		)
		(fp_line
			(start -0.12065 -0.305054)
			(end -0.12065 -0.2794)
			(stroke
				(width 0.1)
				(type default)
			)
			(layer "F.Fab")
		)
		(fp_line
			(start -0.67945 0.3048)
			(end -0.67945 -0.305054)
			(stroke
				(width 0.1)
				(type default)
			)
			(layer "F.Fab")
		)
		(fp_line
			(start -0.67945 -0.305054)
			(end -0.12065 -0.305054)
			(stroke
				(width 0.1)
				(type default)
			)
			(layer "F.Fab")
		)
		(pad "1" smd circle
			(at -0.40005 0 180)
			(size 0 0)
			(layers "F.Cu" "F.Mask" "F.Paste")
			(net "GND")
		)
		(pad "2" smd circle
			(at 0.40005 0 180)
			(size 0 0)
			(layers "F.Cu" "F.Mask" "F.Paste")
			(net "U403_ADD0")
		)
	)
)
